FILE_TYPE = MACRO_DRAWING;
SET COLOR_WIRE YELLOW;
SET COLOR_PROP ORANGE;
SET COLOR_DOT WHITE;
SET COLOR_ARC YELLOW;
SET COLOR_BODY GREEN;
SET COLOR_NOTE PURPLE;
SET PROP_DISPLAY VALUE;
SET PAGE_NUMBER P35;
FORCEADD QUANTA_TITLE_BLOCK_C..1
(0 0);
FORCEPROP 1 LAST CUSTOM_TXT_CDS <NAME_2>
J 0
(-3175 50);
FORCEPROP 1 LAST CUSTOM_TXT_CDS <NAME_1>
J 0
(-3175 175);
FORCEPROP 1 LAST CUSTOM_TXT_CDS <Q_NUMBER>
J 0
(-1403 103);
DISPLAY 1.212766 (-1403 103);
FORCEPROP 1 LAST CUSTOM_TXT_CDS <Q_PROJ>
J 0
(-2382 102);
DISPLAY 1.212766 (-2382 102);
FORCEPROP 1 LAST CUSTOM_TXT_CDS <Q_REV>
J 0
(-184 103);
DISPLAY 1.212766 (-184 103);
FORCEPROP 1 LAST CUSTOM_TXT_CDS <CON_LAST_MODIFIED>
J 0
(-1885 15);
DISPLAY 0.978723 (-1885 15);
FORCEPROP 1 LAST CUSTOM_TXT_CDS <CON_PAGE_NUM> OF <CON_TOTAL_PAGES>
J 0
(-446 18);
DISPLAY 0.978723 (-446 18);
FORCEPROP 1 LAST Q_DEPT BU9
J 1
(-3763 49);
DISPLAY 1.957447 (-3763 49);
PAINT GREEN (-3763 49);
FORCEPROP 1 LAST Q_TITLE Blank
J 0
(-9275 100);
DISPLAY 2.446809 (-9275 100);
PAINT GREEN (-9275 100);
FORCEPROP 0 LAST CDS_CON_LAST_MODIFIED Wed Jul 21 11:34:34 2021
J 0
(-1885 15);
DISPLAY INVISIBLE (-1885 15);
FORCEPROP 1 LAST CDS_LMAN_SYM_OUTLINE -9475,6775,100,-125
J 0
(0 0);
DISPLAY 0.468085 (0 0);
PAINT GREEN (0 0);
DISPLAY INVISIBLE (0 0);
FORCEPROP 2 LAST CDS_LIB pure_quanta
J 0
(0 0);
DISPLAY INVISIBLE (0 0);
FORCEPROP 2 LAST PAGE_BORDER TRUE
J 0
(-7890 5250);
DISPLAY 0.638298 (-7890 5250);
PAINT PINK (-7890 5250);
DISPLAY INVISIBLE (-7890 5250);
FORCEPROP 1 LAST COMMENT_BODY TRUE
J 0
(12 -13);
DISPLAY 0.978723 (12 -13);
PAINT GREEN (12 -13);
DISPLAY INVISIBLE (12 -13);
FORCEPROP 2 LAST CUSTOM_TXT_CDS <XR_PAGE_TITLE>
J 0
(-7890 5250);
DISPLAY 0.638298 (-7890 5250);
PAINT PINK (-7890 5250);
DISPLAY INVISIBLE (-7890 5250);
FORCEPROP 2 LAST CDS_XR_PAGE_TITLE CR-35 : @T6G_MB_LIB.T6G(SCH_1):PAGE35
J 0
(-7890 5250);
DISPLAY 0.638298 (-7890 5250);
PAINT PINK (-7890 5250);
DISPLAY INVISIBLE (-7890 5250);
QUIT
